(kicad_pcb
	(version 20260206)
	(generator "pcbnew")
	(generator_version "10.0")
	(general
		(thickness 1.6)
		(legacy_teardrops no)
	)
	(paper "A4")
	(title_block
		(title "fcb — 12433-1M.1206WZS1330.brd")
		(comment 1 "Open Vault / Knox (Wiwynn) / footprints 13-15 of 495")
	)
	(layers
		(0 "F.Cu" signal "TOP")
		(4 "In1.Cu" signal "L2GND")
		(6 "In2.Cu" signal "L3VCC")
		(2 "B.Cu" signal "BOTTOM")
		(9 "F.Adhes" user "F.Adhesive")
		(11 "B.Adhes" user "B.Adhesive")
		(13 "F.Paste" user "Package Geometry/Pastemask Top")
		(15 "B.Paste" user "Package Geometry/Pastemask Bottom")
		(5 "F.SilkS" user "Ref Des/Silkscreen Top")
		(7 "B.SilkS" user "Ref Des/Silkscreen Bottom")
		(1 "F.Mask" user "Board Geometry/Soldermask Top")
		(3 "B.Mask" user "Board Geometry/Soldermask Bottom")
		(17 "Dwgs.User" user "User.Drawings")
		(19 "Cmts.User" user "User.Comments")
		(21 "Eco1.User" user "User.Eco1")
		(23 "Eco2.User" user "User.Eco2")
		(25 "Edge.Cuts" user "Board Geometry/Outline")
		(27 "Margin" user)
		(31 "F.CrtYd" user "Package Geometry/Place Bound Top")
		(29 "B.CrtYd" user "Package Geometry/Place Bound Bottom")
		(35 "F.Fab" user "Ref Des/Assembly Top")
		(33 "B.Fab" user "Ref Des/Assembly Bottom")
	)
	(footprint ""
		(layer "F.Cu")
		(at 13.97 -174.752 90)
		(property "Reference" "U11"
			(at 0 0 90)
			(layer "F.SilkS")
			(hide yes)
			(effects
				(font
					(size 1.27 1.27)
				)
			)
		)
		(property "Value" "74LVC1G32GW-1GP"
			(at -2.3368 -8.6868 90)
			(unlocked yes)
			(layer "F.Fab")
			(hide yes)
			(effects
				(font
					(size 1.016 1.016)
					(thickness 0.1524)
				)
			)
		)
		(property "Device Type" "SC70-5H44"
			(at -2.3114 -10.414 90)
			(unlocked yes)
			(layer "F.Fab")
			(hide yes)
			(effects
				(font
					(size 1.016 1.016)
					(thickness 0.1524)
				)
			)
		)
		(duplicate_pad_numbers_are_jumpers no)
		(fp_line
			(start 1.3843 -1.8034)
			(end 1.3843 -1.1176)
			(stroke
				(width 0.3302)
				(type default)
			)
			(layer "F.SilkS")
		)
		(fp_line
			(start 0.6604 -1.8034)
			(end 1.3843 -1.8034)
			(stroke
				(width 0.3302)
				(type default)
			)
			(layer "F.SilkS")
		)
		(fp_line
			(start 1.27 -1.7018)
			(end 1.27 1.7018)
			(stroke
				(width 0.1524)
				(type default)
			)
			(layer "F.SilkS")
		)
		(fp_line
			(start -1.27 -1.7018)
			(end 1.27 -1.7018)
			(stroke
				(width 0.1524)
				(type default)
			)
			(layer "F.SilkS")
		)
		(fp_line
			(start 1.27 1.7018)
			(end -1.27 1.7018)
			(stroke
				(width 0.1524)
				(type default)
			)
			(layer "F.SilkS")
		)
		(fp_line
			(start -1.27 1.7018)
			(end -1.27 -1.7018)
			(stroke
				(width 0.1524)
				(type default)
			)
			(layer "F.SilkS")
		)
		(fp_rect
			(start -1.524 1.9558)
			(end 1.524 -1.9558)
			(stroke
				(width 0)
				(type default)
			)
			(fill no)
			(layer "F.CrtYd")
		)
		(fp_poly
			(pts
				(xy -1.524 -1.9558) (xy 1.524 -1.9558) (xy 1.524 1.9558) (xy -1.524 1.9558)
			)
			(stroke
				(width 0)
				(type default)
			)
			(fill no)
			(layer "F.Fab")
		)
		(pad "1" smd rect
			(at 0.65024 -0.8255 90)
			(size 0.4064 1.2192)
			(layers "F.Cu" "F.Mask" "F.Paste")
			(net "SEB_PEER_2A_HB")
		)
		(pad "2" smd rect
			(at 0 -0.8255 90)
			(size 0.4064 1.2192)
			(layers "F.Cu" "F.Mask" "F.Paste")
			(net "SEB_PEER_2B_HB")
		)
		(pad "3" smd rect
			(at -0.65024 -0.8255 90)
			(size 0.4064 1.2192)
			(layers "F.Cu" "F.Mask" "F.Paste")
			(net "GND")
		)
		(pad "4" smd rect
			(at -0.65024 0.8255 90)
			(size 0.4064 1.2192)
			(layers "F.Cu" "F.Mask" "F.Paste")
			(net "SEB_PEER_2A_2B_HB_OUT")
		)
		(pad "5" smd rect
			(at 0.65024 0.8255 90)
			(size 0.4064 1.2192)
			(layers "F.Cu" "F.Mask" "F.Paste")
			(net "P3V3")
		)
	)
	(footprint ""
		(layer "F.Cu")
		(at 14.5796 -171.4754)
		(property "Reference" "R49"
			(at 0 0 0)
			(layer "F.SilkS")
			(hide yes)
			(effects
				(font
					(size 1.27 1.27)
				)
			)
		)
		(property "Value" "4K7R2F-GP"
			(at 0.064008 -3.993896 0)
			(unlocked yes)
			(layer "F.Fab")
			(hide yes)
			(effects
				(font
					(size 1.016 1.016)
					(thickness 0.1524)
				)
			)
		)
		(property "Device Type" "R402H16"
			(at 0.064008 -5.517896 0)
			(unlocked yes)
			(layer "F.Fab")
			(hide yes)
			(effects
				(font
					(size 1.016 1.016)
					(thickness 0.1524)
				)
			)
		)
		(duplicate_pad_numbers_are_jumpers no)
		(fp_line
			(start -0.508 -0.9398)
			(end -0.508 0.9398)
			(stroke
				(width 0.1524)
				(type default)
			)
			(layer "F.SilkS")
		)
		(fp_line
			(start 0.508 -0.9398)
			(end -0.508 -0.9398)
			(stroke
				(width 0.1524)
				(type default)
			)
			(layer "F.SilkS")
		)
		(fp_rect
			(start -0.508 0.9398)
			(end 0.508 -0.9398)
			(stroke
				(width 0)
				(type default)
			)
			(fill no)
			(layer "F.CrtYd")
		)
		(fp_rect
			(start -0.508 0.9398)
			(end 0.508 -0.9398)
			(stroke
				(width 0)
				(type default)
			)
			(fill no)
			(layer "F.Fab")
		)
		(pad "1" smd custom
			(at 0 -0.4445)
			(size 0.1397 0.1397)
			(layers "F.Cu" "F.Mask" "F.Paste")
			(net "P3V3")
			(options
				(clearance outline)
				(anchor circle)
			)
			(primitives
				(gr_poly
					(pts
						(arc
							(start -0.1778 -0.2794)
							(mid -0.249642 -0.249642)
							(end -0.2794 -0.1778)
						)
						(arc
							(start -0.2794 0.1778)
							(mid -0.249642 0.249642)
							(end -0.1778 0.2794)
						)
						(arc
							(start 0.1778 0.2794)
							(mid 0.249642 0.249642)
							(end 0.2794 0.1778)
						)
						(arc
							(start 0.2794 -0.1778)
							(mid 0.249642 -0.249642)
							(end 0.1778 -0.2794)
						)
					)
					(width 0)
					(fill yes)
				)
			)
		)
		(pad "2" smd custom
			(at 0 0.4445)
			(size 0.1397 0.1397)
			(layers "F.Cu" "F.Mask" "F.Paste")
			(net "SEB_PEER_1A_1B_HB_OUT")
			(options
				(clearance outline)
				(anchor circle)
			)
			(primitives
				(gr_poly
					(pts
						(arc
							(start -0.1778 -0.2794)
							(mid -0.249642 -0.249642)
							(end -0.2794 -0.1778)
						)
						(arc
							(start -0.2794 0.1778)
							(mid -0.249642 0.249642)
							(end -0.1778 0.2794)
						)
						(arc
							(start 0.1778 0.2794)
							(mid 0.249642 0.249642)
							(end 0.2794 0.1778)
						)
						(arc
							(start 0.2794 -0.1778)
							(mid 0.249642 -0.249642)
							(end 0.1778 -0.2794)
						)
					)
					(width 0)
					(fill yes)
				)
			)
		)
	)
	(footprint ""
		(layer "F.Cu")
		(at 45.500036 -294.999918)
		(property "Reference" "H6"
			(at 0 0 0)
			(layer "F.SilkS")
			(hide yes)
			(effects
				(font
					(size 1.27 1.27)
				)
			)
		)
		(property "Value" "HOLE315R138"
			(at 0 -7.0612 0)
			(unlocked yes)
			(layer "F.Fab")
			(hide yes)
			(effects
				(font
					(size 1.016 1.016)
					(thickness 0.1524)
				)
			)
		)
		(property "Device Type" "HOLE315R138"
			(at 0 -8.5852 0)
			(unlocked yes)
			(layer "F.Fab")
			(hide yes)
			(effects
				(font
					(size 1.016 1.016)
					(thickness 0.1524)
				)
			)
		)
		(duplicate_pad_numbers_are_jumpers no)
		(fp_poly
			(pts
				(xy 0 4.3053) (xy -0.13462 4.30276) (xy -0.27051 4.29641) (xy -0.40513 4.28625) (xy -0.53975 4.27101)
				(xy -0.6731 4.25196) (xy -0.80645 4.2291) (xy -0.9398 4.20116) (xy -1.07061 4.17068) (xy -1.20142 4.13385)
				(xy -1.33096 4.09448) (xy -1.45796 4.0513) (xy -1.58496 4.00304) (xy -1.70942 3.95097) (xy -1.83261 3.89509)
				(xy -1.95453 3.83667) (xy -2.07391 3.77317) (xy -2.19202 3.70586) (xy -2.30632 3.63474) (xy -2.41935 3.56108)
				(xy -2.53111 3.48361) (xy -2.63906 3.40233) (xy -2.74447 3.31724) (xy -2.84734 3.22961) (xy -2.94767 3.13817)
				(xy -3.04419 3.04419) (xy -3.13817 2.94767) (xy -3.22961 2.84734) (xy -3.31724 2.74447) (xy -3.40233 2.63906)
				(xy -3.48361 2.53111) (xy -3.56108 2.41935) (xy -3.63474 2.30632) (xy -3.70586 2.19202) (xy -3.77317 2.07391)
				(xy -3.83667 1.95453) (xy -3.89509 1.83261) (xy -3.95097 1.70942) (xy -4.00304 1.58496) (xy -4.0513 1.45796)
				(xy -4.09448 1.33096) (xy -4.13385 1.20142) (xy -4.17068 1.07061) (xy -4.20116 0.9398) (xy -4.2291 0.80645)
				(xy -4.25196 0.6731) (xy -4.27101 0.53975) (xy -4.28625 0.40513) (xy -4.29641 0.27051) (xy -4.30276 0.13462)
				(xy -4.3053 0) (xy -4.30276 -0.13462) (xy -4.29641 -0.27051) (xy -4.28625 -0.40513) (xy -4.27101 -0.53975)
				(xy -4.25196 -0.6731) (xy -4.2291 -0.80645) (xy -4.20116 -0.9398) (xy -4.17068 -1.07061) (xy -4.13385 -1.20142)
				(xy -4.09448 -1.33096) (xy -4.0513 -1.45796) (xy -4.00304 -1.58496) (xy -3.95097 -1.70942) (xy -3.89509 -1.83261)
				(xy -3.83667 -1.95453) (xy -3.77317 -2.07391) (xy -3.70586 -2.19202) (xy -3.63474 -2.30632) (xy -3.56108 -2.41935)
				(xy -3.48361 -2.53111) (xy -3.40233 -2.63906) (xy -3.31724 -2.74447) (xy -3.22961 -2.84734) (xy -3.13817 -2.94767)
				(xy -3.04419 -3.04419) (xy -2.94767 -3.13817) (xy -2.84734 -3.22961) (xy -2.74447 -3.31724) (xy -2.63906 -3.40233)
				(xy -2.53111 -3.48361) (xy -2.41935 -3.56108) (xy -2.30632 -3.63474) (xy -2.19202 -3.70586) (xy -2.07391 -3.77317)
				(xy -1.95453 -3.83667) (xy -1.83261 -3.89509) (xy -1.70942 -3.95097) (xy -1.58496 -4.00304) (xy -1.45796 -4.0513)
				(xy -1.33096 -4.09448) (xy -1.20142 -4.13385) (xy -1.07061 -4.17068) (xy -0.9398 -4.20116) (xy -0.80645 -4.2291)
				(xy -0.6731 -4.25196) (xy -0.53975 -4.27101) (xy -0.40513 -4.28625) (xy -0.27051 -4.29641) (xy -0.13462 -4.30276)
				(xy 0 -4.3053) (xy 0.13462 -4.30276) (xy 0.27051 -4.29641) (xy 0.40513 -4.28625) (xy 0.53975 -4.27101)
				(xy 0.6731 -4.25196) (xy 0.80645 -4.2291) (xy 0.9398 -4.20116) (xy 1.07061 -4.17068) (xy 1.20142 -4.13385)
				(xy 1.33096 -4.09448) (xy 1.45796 -4.0513) (xy 1.58496 -4.00304) (xy 1.70942 -3.95097) (xy 1.83261 -3.89509)
				(xy 1.95453 -3.83667) (xy 2.07391 -3.77317) (xy 2.19202 -3.70586) (xy 2.30632 -3.63474) (xy 2.41935 -3.56108)
				(xy 2.53111 -3.48361) (xy 2.63906 -3.40233) (xy 2.74447 -3.31724) (xy 2.84734 -3.22961) (xy 2.94767 -3.13817)
				(xy 3.04419 -3.04419) (xy 3.13817 -2.94767) (xy 3.22961 -2.84734) (xy 3.31724 -2.74447) (xy 3.40233 -2.63906)
				(xy 3.48361 -2.53111) (xy 3.56108 -2.41935) (xy 3.63474 -2.30632) (xy 3.70586 -2.19202) (xy 3.77317 -2.07391)
				(xy 3.83667 -1.95453) (xy 3.89509 -1.83261) (xy 3.95097 -1.70942) (xy 4.00304 -1.58496) (xy 4.0513 -1.45796)
				(xy 4.09448 -1.33096) (xy 4.13385 -1.20142) (xy 4.17068 -1.07061) (xy 4.20116 -0.9398) (xy 4.2291 -0.80645)
				(xy 4.25196 -0.6731) (xy 4.27101 -0.53975) (xy 4.28625 -0.40513) (xy 4.29641 -0.27051) (xy 4.30276 -0.13462)
				(xy 4.3053 0) (xy 4.30276 0.13462) (xy 4.29641 0.27051) (xy 4.28625 0.40513) (xy 4.27101 0.53975)
				(xy 4.25196 0.6731) (xy 4.2291 0.80645) (xy 4.20116 0.9398) (xy 4.17068 1.07061) (xy 4.13385 1.20142)
				(xy 4.09448 1.33096) (xy 4.0513 1.45796) (xy 4.00304 1.58496) (xy 3.95097 1.70942) (xy 3.89509 1.83261)
				(xy 3.83667 1.95453) (xy 3.77317 2.07391) (xy 3.70586 2.19202) (xy 3.63474 2.30632) (xy 3.56108 2.41935)
				(xy 3.48361 2.53111) (xy 3.40233 2.63906) (xy 3.31724 2.74447) (xy 3.22961 2.84734) (xy 3.13817 2.94767)
				(xy 3.04419 3.04419) (xy 2.94767 3.13817) (xy 2.84734 3.22961) (xy 2.74447 3.31724) (xy 2.63906 3.40233)
				(xy 2.53111 3.48361) (xy 2.41935 3.56108) (xy 2.30632 3.63474) (xy 2.19202 3.70586) (xy 2.07391 3.77317)
				(xy 1.95453 3.83667) (xy 1.83261 3.89509) (xy 1.70942 3.95097) (xy 1.58496 4.00304) (xy 1.45796 4.0513)
				(xy 1.33096 4.09448) (xy 1.20142 4.13385) (xy 1.07061 4.17068) (xy 0.9398 4.20116) (xy 0.80645 4.2291)
				(xy 0.6731 4.25196) (xy 0.53975 4.27101) (xy 0.40513 4.28625) (xy 0.27051 4.29641) (xy 0.13462 4.30276)
			)
			(stroke
				(width 0)
				(type default)
			)
			(fill no)
			(layer "F.CrtYd")
		)
		(fp_poly
			(pts
				(xy 0 4.3053) (xy -0.13462 4.30276) (xy -0.27051 4.29641) (xy -0.40513 4.28625) (xy -0.53975 4.27101)
				(xy -0.6731 4.25196) (xy -0.80645 4.2291) (xy -0.9398 4.20116) (xy -1.07061 4.17068) (xy -1.20142 4.13385)
				(xy -1.33096 4.09448) (xy -1.45796 4.0513) (xy -1.58496 4.00304) (xy -1.70942 3.95097) (xy -1.83261 3.89509)
				(xy -1.95453 3.83667) (xy -2.07391 3.77317) (xy -2.19202 3.70586) (xy -2.30632 3.63474) (xy -2.41935 3.56108)
				(xy -2.53111 3.48361) (xy -2.63906 3.40233) (xy -2.74447 3.31724) (xy -2.84734 3.22961) (xy -2.94767 3.13817)
				(xy -3.04419 3.04419) (xy -3.13817 2.94767) (xy -3.22961 2.84734) (xy -3.31724 2.74447) (xy -3.40233 2.63906)
				(xy -3.48361 2.53111) (xy -3.56108 2.41935) (xy -3.63474 2.30632) (xy -3.70586 2.19202) (xy -3.77317 2.07391)
				(xy -3.83667 1.95453) (xy -3.89509 1.83261) (xy -3.95097 1.70942) (xy -4.00304 1.58496) (xy -4.0513 1.45796)
				(xy -4.09448 1.33096) (xy -4.13385 1.20142) (xy -4.17068 1.07061) (xy -4.20116 0.9398) (xy -4.2291 0.80645)
				(xy -4.25196 0.6731) (xy -4.27101 0.53975) (xy -4.28625 0.40513) (xy -4.29641 0.27051) (xy -4.30276 0.13462)
				(xy -4.3053 0) (xy -4.30276 -0.13462) (xy -4.29641 -0.27051) (xy -4.28625 -0.40513) (xy -4.27101 -0.53975)
				(xy -4.25196 -0.6731) (xy -4.2291 -0.80645) (xy -4.20116 -0.9398) (xy -4.17068 -1.07061) (xy -4.13385 -1.20142)
				(xy -4.09448 -1.33096) (xy -4.0513 -1.45796) (xy -4.00304 -1.58496) (xy -3.95097 -1.70942) (xy -3.89509 -1.83261)
				(xy -3.83667 -1.95453) (xy -3.77317 -2.07391) (xy -3.70586 -2.19202) (xy -3.63474 -2.30632) (xy -3.56108 -2.41935)
				(xy -3.48361 -2.53111) (xy -3.40233 -2.63906) (xy -3.31724 -2.74447) (xy -3.22961 -2.84734) (xy -3.13817 -2.94767)
				(xy -3.04419 -3.04419) (xy -2.94767 -3.13817) (xy -2.84734 -3.22961) (xy -2.74447 -3.31724) (xy -2.63906 -3.40233)
				(xy -2.53111 -3.48361) (xy -2.41935 -3.56108) (xy -2.30632 -3.63474) (xy -2.19202 -3.70586) (xy -2.07391 -3.77317)
				(xy -1.95453 -3.83667) (xy -1.83261 -3.89509) (xy -1.70942 -3.95097) (xy -1.58496 -4.00304) (xy -1.45796 -4.0513)
				(xy -1.33096 -4.09448) (xy -1.20142 -4.13385) (xy -1.07061 -4.17068) (xy -0.9398 -4.20116) (xy -0.80645 -4.2291)
				(xy -0.6731 -4.25196) (xy -0.53975 -4.27101) (xy -0.40513 -4.28625) (xy -0.27051 -4.29641) (xy -0.13462 -4.30276)
				(xy 0 -4.3053) (xy 0.13462 -4.30276) (xy 0.27051 -4.29641) (xy 0.40513 -4.28625) (xy 0.53975 -4.27101)
				(xy 0.6731 -4.25196) (xy 0.80645 -4.2291) (xy 0.9398 -4.20116) (xy 1.07061 -4.17068) (xy 1.20142 -4.13385)
				(xy 1.33096 -4.09448) (xy 1.45796 -4.0513) (xy 1.58496 -4.00304) (xy 1.70942 -3.95097) (xy 1.83261 -3.89509)
				(xy 1.95453 -3.83667) (xy 2.07391 -3.77317) (xy 2.19202 -3.70586) (xy 2.30632 -3.63474) (xy 2.41935 -3.56108)
				(xy 2.53111 -3.48361) (xy 2.63906 -3.40233) (xy 2.74447 -3.31724) (xy 2.84734 -3.22961) (xy 2.94767 -3.13817)
				(xy 3.04419 -3.04419) (xy 3.13817 -2.94767) (xy 3.22961 -2.84734) (xy 3.31724 -2.74447) (xy 3.40233 -2.63906)
				(xy 3.48361 -2.53111) (xy 3.56108 -2.41935) (xy 3.63474 -2.30632) (xy 3.70586 -2.19202) (xy 3.77317 -2.07391)
				(xy 3.83667 -1.95453) (xy 3.89509 -1.83261) (xy 3.95097 -1.70942) (xy 4.00304 -1.58496) (xy 4.0513 -1.45796)
				(xy 4.09448 -1.33096) (xy 4.13385 -1.20142) (xy 4.17068 -1.07061) (xy 4.20116 -0.9398) (xy 4.2291 -0.80645)
				(xy 4.25196 -0.6731) (xy 4.27101 -0.53975) (xy 4.28625 -0.40513) (xy 4.29641 -0.27051) (xy 4.30276 -0.13462)
				(xy 4.3053 0) (xy 4.30276 0.13462) (xy 4.29641 0.27051) (xy 4.28625 0.40513) (xy 4.27101 0.53975)
				(xy 4.25196 0.6731) (xy 4.2291 0.80645) (xy 4.20116 0.9398) (xy 4.17068 1.07061) (xy 4.13385 1.20142)
				(xy 4.09448 1.33096) (xy 4.0513 1.45796) (xy 4.00304 1.58496) (xy 3.95097 1.70942) (xy 3.89509 1.83261)
				(xy 3.83667 1.95453) (xy 3.77317 2.07391) (xy 3.70586 2.19202) (xy 3.63474 2.30632) (xy 3.56108 2.41935)
				(xy 3.48361 2.53111) (xy 3.40233 2.63906) (xy 3.31724 2.74447) (xy 3.22961 2.84734) (xy 3.13817 2.94767)
				(xy 3.04419 3.04419) (xy 2.94767 3.13817) (xy 2.84734 3.22961) (xy 2.74447 3.31724) (xy 2.63906 3.40233)
				(xy 2.53111 3.48361) (xy 2.41935 3.56108) (xy 2.30632 3.63474) (xy 2.19202 3.70586) (xy 2.07391 3.77317)
				(xy 1.95453 3.83667) (xy 1.83261 3.89509) (xy 1.70942 3.95097) (xy 1.58496 4.00304) (xy 1.45796 4.0513)
				(xy 1.33096 4.09448) (xy 1.20142 4.13385) (xy 1.07061 4.17068) (xy 0.9398 4.20116) (xy 0.80645 4.2291)
				(xy 0.6731 4.25196) (xy 0.53975 4.27101) (xy 0.40513 4.28625) (xy 0.27051 4.29641) (xy 0.13462 4.30276)
			)
			(stroke
				(width 0)
				(type default)
			)
			(fill no)
			(layer "F.Fab")
		)
		(pad "1" thru_hole circle
			(at 0 0)
			(size 8.001 8.001)
			(drill 3.5052)
			(layers "*.Cu" "*.Mask")
			(remove_unused_layers no)
			(net "GND")
			(clearance -1.7399)
			(thermal_gap 0.3048)
			(padstack
				(mode front_inner_back)
				(layer "Inner"
					(shape circle)
					(size 3.9116 3.9116)
					(clearance 0.3048)
				)
				(layer "B.Cu"
					(shape circle)
					(size 8.001 8.001)
					(clearance -1.7399)
				)
			)
		)
	)
)
